# T6G (Grand Teton) — schematic netlist excerpt (pin names and nets, part order shuffled) for the footprints in the layout excerpt that follows; sources: Cadence DE-HDL packaged netlist, KiCad conversion of 04192023_DAF0TMB3IC0_F0TG_MB_C_brd_V02_OCP.brd

C1133  Q_CAP  0.1UF 16V 10% X7R  pkg C0402  page 83 : A = P1V8_AUX ; B = GND
C1093  Q_CAP  0.1UF 25V 10% X7R  pkg 0402  page 258 : A = P5V_AUX_ADC_TIC ; B = GND

(kicad_pcb
	(version 20260206)
	(generator "pcbnew")
	(generator_version "10.0")
	(general
		(thickness 1.6)
		(legacy_teardrops no)
	)
	(paper "A4")
	(title_block
		(title "04192023_DAF0TMB3IC0_F0TG_MB_C_brd_V02_OCP.brd")
		(comment 1 "Grand Teton / footprints 7641-7642 of 8354")
	)
	(layers
		(0 "F.Cu" signal "TOP")
		(4 "In1.Cu" signal "GND")
		(6 "In2.Cu" signal "IN1")
		(8 "In3.Cu" signal "GND1")
		(10 "In4.Cu" signal "IN2")
		(12 "In5.Cu" signal "GND2")
		(14 "In6.Cu" signal "IN3")
		(16 "In7.Cu" signal "GND3")
		(18 "In8.Cu" signal "VCC")
		(20 "In9.Cu" signal "VCC1")
		(22 "In10.Cu" signal "GND4")
		(24 "In11.Cu" signal "IN4")
		(26 "In12.Cu" signal "GND5")
		(28 "In13.Cu" signal "IN5")
		(30 "In14.Cu" signal "GND6")
		(32 "In15.Cu" signal "IN6")
		(34 "In16.Cu" signal "GND7")
		(2 "B.Cu" signal "BOTTOM")
		(9 "F.Adhes" user "F.Adhesive")
		(11 "B.Adhes" user "B.Adhesive")
		(13 "F.Paste" user "Package Geometry/Pastemask Top")
		(15 "B.Paste" user "Package Geometry/Pastemask Bottom")
		(5 "F.SilkS" user "Ref Des/Silkscreen Top")
		(7 "B.SilkS" user "Ref Des/Silkscreen Bottom")
		(1 "F.Mask" user "Board Geometry/Soldermask Top")
		(3 "B.Mask" user "Board Geometry/Soldermask Bottom")
		(17 "Dwgs.User" user "User.Drawings")
		(19 "Cmts.User" user "User.Comments")
		(21 "Eco1.User" user "User.Eco1")
		(23 "Eco2.User" user "User.Eco2")
		(25 "Edge.Cuts" user "Board Geometry/Outline")
		(27 "Margin" user)
		(31 "F.CrtYd" user "Package Geometry/Place Bound Top")
		(29 "B.CrtYd" user "Package Geometry/Place Bound Bottom")
		(35 "F.Fab" user "Ref Des/Assembly Top")
		(33 "B.Fab" user "Ref Des/Assembly Bottom")
	)
	(footprint ""
		(layer "B.Cu")
		(at 186.711844 -117.442996 90)
		(property "Reference" "C1133"
			(at 0 0 90)
			(layer "B.SilkS")
			(hide yes)
			(effects
				(font
					(size 1.27 1.27)
				)
				(justify mirror)
			)
		)
		(property "Value" ""
			(at 0 0 90)
			(layer "B.Fab")
			(effects
				(font
					(size 1.27 1.27)
				)
				(justify mirror)
			)
		)
		(duplicate_pad_numbers_are_jumpers no)
		(fp_line
			(start 0.69215 -0.2921)
			(end -0.69215 -0.2921)
			(stroke
				(width 0.1524)
				(type default)
			)
			(layer "B.SilkS")
		)
		(fp_line
			(start -0.69215 -0.2921)
			(end -0.69215 0.2921)
			(stroke
				(width 0.1524)
				(type default)
			)
			(layer "B.SilkS")
		)
		(fp_line
			(start 0.69215 0.2921)
			(end 0.69215 -0.2921)
			(stroke
				(width 0.1524)
				(type default)
			)
			(layer "B.SilkS")
		)
		(fp_line
			(start -0.69215 0.2921)
			(end 0.69215 0.2921)
			(stroke
				(width 0.1524)
				(type default)
			)
			(layer "B.SilkS")
		)
		(fp_line
			(start 0.51435 -0.2794)
			(end -0.51435 -0.2794)
			(stroke
				(width 0.1)
				(type default)
			)
			(layer "B.Fab")
		)
		(fp_line
			(start -0.51435 -0.2794)
			(end -0.51435 0.2794)
			(stroke
				(width 0.1)
				(type default)
			)
			(layer "B.Fab")
		)
		(fp_line
			(start 0.51435 0.2794)
			(end 0.51435 -0.2794)
			(stroke
				(width 0.1)
				(type default)
			)
			(layer "B.Fab")
		)
		(fp_line
			(start -0.51435 0.2794)
			(end 0.51435 0.2794)
			(stroke
				(width 0.1)
				(type default)
			)
			(layer "B.Fab")
		)
		(pad "1" smd circle
			(at 0.40005 0 270)
			(size 0 0)
			(layers "B.Cu" "B.Mask" "B.Paste")
			(net "P1V8_AUX")
		)
		(pad "2" smd circle
			(at -0.40005 0 270)
			(size 0 0)
			(layers "B.Cu" "B.Mask" "B.Paste")
			(net "GND")
		)
		(zone
			(layer "B.Cu")
			(hatch none 0.5)
			(connect_pads
				(clearance 0)
			)
			(min_thickness 0.25)
			(keepout
				(tracks not_allowed)
				(vias allowed)
				(pads allowed)
				(copperpour not_allowed)
				(footprints allowed)
			)
			(placement
				(enabled no)
				(sheetname "")
			)
			(fill
				(thermal_gap 0.5)
				(thermal_bridge_width 0.5)
				(island_removal_mode 0)
			)
			(polygon
				(pts
					(xy 186.565794 -117.342666) (xy 186.565794 -117.542056) (xy 186.62396 -117.633496) (xy 186.799474 -117.633496)
					(xy 186.85764 -117.542056) (xy 186.85764 -117.342666) (xy 186.799474 -117.252496) (xy 186.624214 -117.252496)
				)
			)
		)
	)
	(footprint ""
		(layer "B.Cu")
		(at 228.494082 -322.17868 180)
		(property "Reference" "C1093"
			(at 0 0 0)
			(layer "B.SilkS")
			(hide yes)
			(effects
				(font
					(size 1.27 1.27)
				)
				(justify mirror)
			)
		)
		(property "Value" ""
			(at 0 0 0)
			(layer "B.Fab")
			(effects
				(font
					(size 1.27 1.27)
				)
				(justify mirror)
			)
		)
		(duplicate_pad_numbers_are_jumpers no)
		(fp_line
			(start 0.7874 0.4064)
			(end 0.7874 -0.4064)
			(stroke
				(width 0.1524)
				(type default)
			)
			(layer "B.SilkS")
		)
		(fp_line
			(start 0.7874 -0.4064)
			(end -0.7874 -0.4064)
			(stroke
				(width 0.1524)
				(type default)
			)
			(layer "B.SilkS")
		)
		(fp_line
			(start -0.7874 0.4064)
			(end 0.7874 0.4064)
			(stroke
				(width 0.1524)
				(type default)
			)
			(layer "B.SilkS")
		)
		(fp_line
			(start -0.7874 -0.4064)
			(end -0.7874 0.4064)
			(stroke
				(width 0.1524)
				(type default)
			)
			(layer "B.SilkS")
		)
		(fp_line
			(start 0.67945 0.3048)
			(end 0.67945 -0.305054)
			(stroke
				(width 0.1)
				(type default)
			)
			(layer "B.Fab")
		)
		(fp_line
			(start 0.67945 -0.305054)
			(end 0.12065 -0.305054)
			(stroke
				(width 0.1)
				(type default)
			)
			(layer "B.Fab")
		)
		(fp_line
			(start 0.12065 0.3048)
			(end 0.67945 0.3048)
			(stroke
				(width 0.1)
				(type default)
			)
			(layer "B.Fab")
		)
		(fp_line
			(start 0.12065 0.2794)
			(end 0.12065 0.3048)
			(stroke
				(width 0.1)
				(type default)
			)
			(layer "B.Fab")
		)
		(fp_line
			(start 0.12065 -0.2794)
			(end -0.12065 -0.2794)
			(stroke
				(width 0.1)
				(type default)
			)
			(layer "B.Fab")
		)
		(fp_line
			(start 0.12065 -0.305054)
			(end 0.12065 -0.2794)
			(stroke
				(width 0.1)
				(type default)
			)
			(layer "B.Fab")
		)
		(fp_line
			(start -0.120396 0.3048)
			(end -0.120396 0.2794)
			(stroke
				(width 0.1)
				(type default)
			)
			(layer "B.Fab")
		)
		(fp_line
			(start -0.120396 0.2794)
			(end 0.12065 0.2794)
			(stroke
				(width 0.1)
				(type default)
			)
			(layer "B.Fab")
		)
		(fp_line
			(start -0.12065 -0.2794)
			(end -0.12065 -0.3048)
			(stroke
				(width 0.1)
				(type default)
			)
			(layer "B.Fab")
		)
		(fp_line
			(start -0.12065 -0.3048)
			(end -0.67945 -0.3048)
			(stroke
				(width 0.1)
				(type default)
			)
			(layer "B.Fab")
		)
		(fp_line
			(start -0.67945 0.3048)
			(end -0.120396 0.3048)
			(stroke
				(width 0.1)
				(type default)
			)
			(layer "B.Fab")
		)
		(fp_line
			(start -0.67945 -0.3048)
			(end -0.67945 0.3048)
			(stroke
				(width 0.1)
				(type default)
			)
			(layer "B.Fab")
		)
		(pad "1" smd circle
			(at 0.40005 0)
			(size 0 0)
			(layers "B.Cu" "B.Mask" "B.Paste")
			(net "P5V_AUX_ADC_TIC")
		)
		(pad "2" smd circle
			(at -0.40005 0)
			(size 0 0)
			(layers "B.Cu" "B.Mask" "B.Paste")
			(net "GND")
		)
	)
)
